(kicad_pcb
	(version 20241229)
	(generator "pcbnew")
	(generator_version "9.0")
	(general
		(thickness 1.294)
		(legacy_teardrops no)
	)
	(paper "A3")
	(title_block
		(title "Kintex 410T devboard")
		(date "2024-04-03")
		(rev "1.1.2")
		(comment 9 "footprints 876-880 of 975")
	)
	(layers
		(0 "F.Cu" mixed)
		(4 "In1.Cu" power)
		(6 "In2.Cu" power)
		(8 "In3.Cu" mixed)
		(10 "In4.Cu" power)
		(12 "In5.Cu" mixed)
		(14 "In6.Cu" power)
		(16 "In7.Cu" mixed)
		(18 "In8.Cu" power)
		(2 "B.Cu" mixed)
		(9 "F.Adhes" user "F.Adhesive")
		(11 "B.Adhes" user "B.Adhesive")
		(13 "F.Paste" user)
		(15 "B.Paste" user)
		(5 "F.SilkS" user "F.Silkscreen")
		(7 "B.SilkS" user "B.Silkscreen")
		(1 "F.Mask" user)
		(3 "B.Mask" user)
		(17 "Dwgs.User" user "User.Drawings")
		(19 "Cmts.User" user "User.Comments")
		(21 "Eco1.User" user "User.Eco1")
		(23 "Eco2.User" user "User.Eco2")
		(25 "Edge.Cuts" user)
		(27 "Margin" user)
		(31 "F.CrtYd" user "F.Courtyard")
		(29 "B.CrtYd" user "B.Courtyard")
		(35 "F.Fab" user)
		(33 "B.Fab" user)
	)
	(footprint "antmicro-footprints:C_0402_1005Metric"
		(layer "B.Cu")
		(at 186.5 187.5 180)
		(descr "Capacitor SMD 0402")
		(tags "capacitor SMD 0402")
		(property "Reference" "C321"
			(at -1.475 -1.275 0)
			(layer "B.SilkS")
			(effects
				(font
					(size 0.7 0.7)
					(thickness 0.15)
				)
				(justify left bottom mirror)
			)
		)
		(property "Value" "C_1u_0402"
			(at 0 -1.4 0)
			(layer "B.Fab")
			(effects
				(font
					(size 0.7 0.7)
					(thickness 0.15)
				)
				(justify left bottom mirror)
			)
		)
		(property "Description" "SMD Multilayer Ceramic Capacitor, 1 µF, 10 V, 0402 [1005 Metric], ± 10%, X6S, C"
			(at 0 0 180)
			(layer "F.Fab")
			(hide yes)
			(effects
				(font
					(size 1.27 1.27)
					(thickness 0.15)
				)
			)
		)
		(property "Author" "Antmicro"
			(at 373 375 0)
			(layer "B.Fab")
			(hide yes)
			(effects
				(font
					(size 1 1)
					(thickness 0.15)
				)
				(justify mirror)
			)
		)
		(property "Dielectric" ""
			(at 373 375 0)
			(layer "B.Fab")
			(hide yes)
			(effects
				(font
					(size 1 1)
					(thickness 0.15)
				)
				(justify mirror)
			)
		)
		(property "License" "Apache-2.0"
			(at 373 375 0)
			(layer "B.Fab")
			(hide yes)
			(effects
				(font
					(size 1 1)
					(thickness 0.15)
				)
				(justify mirror)
			)
		)
		(property "MPN" "C1005X6S1A105K050BC"
			(at 373 375 0)
			(layer "B.Fab")
			(hide yes)
			(effects
				(font
					(size 1 1)
					(thickness 0.15)
				)
				(justify mirror)
			)
		)
		(property "Manufacturer" "TDK"
			(at 373 375 0)
			(layer "B.Fab")
			(hide yes)
			(effects
				(font
					(size 1 1)
					(thickness 0.15)
				)
				(justify mirror)
			)
		)
		(property "Val" "1u"
			(at 373 375 0)
			(layer "B.Fab")
			(hide yes)
			(effects
				(font
					(size 1 1)
					(thickness 0.15)
				)
				(justify mirror)
			)
		)
		(property "Voltage" ""
			(at 373 375 0)
			(layer "B.Fab")
			(hide yes)
			(effects
				(font
					(size 1 1)
					(thickness 0.15)
				)
				(justify mirror)
			)
		)
		(sheetname "DC-DC Converters")
		(sheetfile "dc-dc.kicad_sch")
		(attr smd)
		(fp_rect
			(start -0.925 0.47)
			(end 0.925 -0.47)
			(stroke
				(width 0.05)
				(type default)
			)
			(fill no)
			(layer "B.CrtYd")
		)
		(fp_line
			(start 0.504 0.25)
			(end 0.504 -0.248)
			(stroke
				(width 0.15)
				(type solid)
			)
			(layer "B.Fab")
		)
		(fp_line
			(start 0.504 -0.248)
			(end -0.494 -0.248)
			(stroke
				(width 0.15)
				(type solid)
			)
			(layer "B.Fab")
		)
		(fp_line
			(start -0.494 0.25)
			(end 0.504 0.25)
			(stroke
				(width 0.15)
				(type solid)
			)
			(layer "B.Fab")
		)
		(fp_line
			(start -0.494 -0.248)
			(end -0.494 0.25)
			(stroke
				(width 0.15)
				(type solid)
			)
			(layer "B.Fab")
		)
		(pad "1" smd roundrect
			(at -0.48 0 180)
			(size 0.59 0.64)
			(layers "B.Cu" "B.Mask" "B.Paste")
			(roundrect_rratio 0.25)
			(net 1 "GND")
			(pintype "passive")
		)
		(pad "2" smd roundrect
			(at 0.48 0 180)
			(size 0.59 0.64)
			(layers "B.Cu" "B.Mask" "B.Paste")
			(roundrect_rratio 0.25)
			(net 37 "+3V3_AON")
			(pintype "passive")
		)
	)
	(footprint "antmicro-footprints:C_0402_1005Metric"
		(layer "B.Cu")
		(at 214.5 124 -90)
		(descr "Capacitor SMD 0402")
		(tags "capacitor SMD 0402")
		(property "Reference" "C32"
			(at -1.1 0.525 90)
			(layer "B.SilkS")
			(effects
				(font
					(size 0.7 0.7)
					(thickness 0.15)
				)
				(justify left bottom mirror)
			)
		)
		(property "Value" "C_100n_0402"
			(at 0 -1.169 90)
			(layer "B.Fab")
			(effects
				(font
					(size 0.7 0.7)
					(thickness 0.15)
				)
				(justify left bottom mirror)
			)
		)
		(property "Description" "SMD Multilayer Ceramic Capacitor, 0.1 µF, 50 V, 0402 [1005 Metric], ± 10%, X5R, GRM Series"
			(at 0 0 270)
			(layer "F.Fab")
			(hide yes)
			(effects
				(font
					(size 1.27 1.27)
					(thickness 0.15)
				)
			)
		)
		(property "Author" "Antmicro"
			(at 90.5 338.5 0)
			(layer "B.Fab")
			(hide yes)
			(effects
				(font
					(size 1 1)
					(thickness 0.15)
				)
				(justify mirror)
			)
		)
		(property "Dielectric" "X5R"
			(at 90.5 338.5 0)
			(layer "B.Fab")
			(hide yes)
			(effects
				(font
					(size 1 1)
					(thickness 0.15)
				)
				(justify mirror)
			)
		)
		(property "License" "Apache-2.0"
			(at 90.5 338.5 0)
			(layer "B.Fab")
			(hide yes)
			(effects
				(font
					(size 1 1)
					(thickness 0.15)
				)
				(justify mirror)
			)
		)
		(property "MPN" "GRM155R61H104KE14D"
			(at 90.5 338.5 0)
			(layer "B.Fab")
			(hide yes)
			(effects
				(font
					(size 1 1)
					(thickness 0.15)
				)
				(justify mirror)
			)
		)
		(property "Manufacturer" "Murata"
			(at 90.5 338.5 0)
			(layer "B.Fab")
			(hide yes)
			(effects
				(font
					(size 1 1)
					(thickness 0.15)
				)
				(justify mirror)
			)
		)
		(property "Val" "100n"
			(at 90.5 338.5 0)
			(layer "B.Fab")
			(hide yes)
			(effects
				(font
					(size 1 1)
					(thickness 0.15)
				)
				(justify mirror)
			)
		)
		(property "Voltage" "50V"
			(at 90.5 338.5 0)
			(layer "B.Fab")
			(hide yes)
			(effects
				(font
					(size 1 1)
					(thickness 0.15)
				)
				(justify mirror)
			)
		)
		(sheetname "FPGA Bank 14 & 15")
		(sheetfile "fpga-bank-14-15.kicad_sch")
		(attr smd)
		(fp_rect
			(start -0.925 0.47)
			(end 0.925 -0.47)
			(stroke
				(width 0.05)
				(type default)
			)
			(fill no)
			(layer "B.CrtYd")
		)
		(fp_line
			(start -0.494 0.25)
			(end 0.504 0.25)
			(stroke
				(width 0.15)
				(type solid)
			)
			(layer "B.Fab")
		)
		(fp_line
			(start 0.504 0.25)
			(end 0.504 -0.248)
			(stroke
				(width 0.15)
				(type solid)
			)
			(layer "B.Fab")
		)
		(fp_line
			(start -0.494 -0.248)
			(end -0.494 0.25)
			(stroke
				(width 0.15)
				(type solid)
			)
			(layer "B.Fab")
		)
		(fp_line
			(start 0.504 -0.248)
			(end -0.494 -0.248)
			(stroke
				(width 0.15)
				(type solid)
			)
			(layer "B.Fab")
		)
		(pad "1" smd roundrect
			(at -0.48 0 270)
			(size 0.59 0.64)
			(layers "B.Cu" "B.Mask" "B.Paste")
			(roundrect_rratio 0.25)
			(net 1 "GND")
			(pintype "passive")
		)
		(pad "2" smd roundrect
			(at 0.48 0 270)
			(size 0.59 0.64)
			(layers "B.Cu" "B.Mask" "B.Paste")
			(roundrect_rratio 0.25)
			(net 2 "VCC_USR_A")
			(pintype "passive")
		)
	)
	(footprint "antmicro-footprints:C_0201"
		(layer "B.Cu")
		(at 202.65 133.5 -90)
		(descr "Capacitor SMD 0201")
		(tags "capacitor SMD 0201")
		(property "Reference" "C141"
			(at -29.85 -27.025 90)
			(layer "B.SilkS")
			(effects
				(font
					(size 0.7 0.7)
					(thickness 0.15)
				)
				(justify left bottom mirror)
			)
		)
		(property "Value" "C_100n_0201"
			(at 0 -1.4 90)
			(layer "B.Fab")
			(effects
				(font
					(size 0.7 0.7)
					(thickness 0.15)
				)
				(justify left bottom mirror)
			)
		)
		(property "Description" "SMD Multilayer Ceramic Capacitor, 0.1 µF, 6.3 V, 0201 [0603 Metric], ± 10%, X6S, CC Series"
			(at 0 0 270)
			(layer "F.Fab")
			(hide yes)
			(effects
				(font
					(size 1.27 1.27)
					(thickness 0.15)
				)
			)
		)
		(property "Author" "Antmicro"
			(at 69.15 336.15 0)
			(layer "B.Fab")
			(hide yes)
			(effects
				(font
					(size 1 1)
					(thickness 0.15)
				)
				(justify mirror)
			)
		)
		(property "Dielectric" ""
			(at 69.15 336.15 0)
			(layer "B.Fab")
			(hide yes)
			(effects
				(font
					(size 1 1)
					(thickness 0.15)
				)
				(justify mirror)
			)
		)
		(property "License" "Apache-2.0"
			(at 69.15 336.15 0)
			(layer "B.Fab")
			(hide yes)
			(effects
				(font
					(size 1 1)
					(thickness 0.15)
				)
				(justify mirror)
			)
		)
		(property "MPN" "CC0201KRX6S5BB104"
			(at 69.15 336.15 0)
			(layer "B.Fab")
			(hide yes)
			(effects
				(font
					(size 1 1)
					(thickness 0.15)
				)
				(justify mirror)
			)
		)
		(property "Manufacturer" "YAGEO"
			(at 69.15 336.15 0)
			(layer "B.Fab")
			(hide yes)
			(effects
				(font
					(size 1 1)
					(thickness 0.15)
				)
				(justify mirror)
			)
		)
		(property "Val" "100n"
			(at 69.15 336.15 0)
			(layer "B.Fab")
			(hide yes)
			(effects
				(font
					(size 1 1)
					(thickness 0.15)
				)
				(justify mirror)
			)
		)
		(property "Voltage" ""
			(at 69.15 336.15 0)
			(layer "B.Fab")
			(hide yes)
			(effects
				(font
					(size 1 1)
					(thickness 0.15)
				)
				(justify mirror)
			)
		)
		(sheetname "FPGA supply")
		(sheetfile "fpga-supply.kicad_sch")
		(attr smd)
		(fp_rect
			(start -0.7 0.35)
			(end 0.7 -0.35)
			(stroke
				(width 0.05)
				(type default)
			)
			(fill no)
			(layer "B.CrtYd")
		)
		(fp_rect
			(start 0.3 -0.15)
			(end -0.301 0.149)
			(stroke
				(width 0.15)
				(type solid)
			)
			(fill no)
			(layer "B.Fab")
		)
		(pad "" smd roundrect
			(at -0.349 0.002 270)
			(size 0.318 0.36)
			(layers "B.Paste")
			(roundrect_rratio 0.25)
		)
		(pad "" smd roundrect
			(at 0.341 0.002 270)
			(size 0.318 0.36)
			(layers "B.Paste")
			(roundrect_rratio 0.25)
		)
		(pad "1" smd roundrect
			(at -0.321 0.002 270)
			(size 0.46 0.4)
			(layers "B.Cu" "B.Mask")
			(roundrect_rratio 0.25)
			(net 1 "GND")
			(pintype "passive")
		)
		(pad "2" smd roundrect
			(at 0.32 0.002 270)
			(size 0.46 0.4)
			(layers "B.Cu" "B.Mask")
			(roundrect_rratio 0.25)
			(net 650 "+1V0")
			(pintype "passive")
		)
	)
	(footprint "antmicro-footprints:C_0402_1005Metric"
		(layer "B.Cu")
		(at 202.5 123 90)
		(descr "Capacitor SMD 0402")
		(tags "capacitor SMD 0402")
		(property "Reference" "C92"
			(at 31.075 27.025 270)
			(layer "B.SilkS")
			(effects
				(font
					(size 0.7 0.7)
					(thickness 0.15)
				)
				(justify left bottom mirror)
			)
		)
		(property "Value" "C_100n_0402"
			(at 0 -1.169 270)
			(layer "B.Fab")
			(effects
				(font
					(size 0.7 0.7)
					(thickness 0.15)
				)
				(justify left bottom mirror)
			)
		)
		(property "Description" "SMD Multilayer Ceramic Capacitor, 0.1 µF, 50 V, 0402 [1005 Metric], ± 10%, X5R, GRM Series"
			(at 0 0 90)
			(layer "F.Fab")
			(hide yes)
			(effects
				(font
					(size 1.27 1.27)
					(thickness 0.15)
				)
			)
		)
		(property "Author" "Antmicro"
			(at 325.5 -79.5 0)
			(layer "B.Fab")
			(hide yes)
			(effects
				(font
					(size 1 1)
					(thickness 0.15)
				)
				(justify mirror)
			)
		)
		(property "Dielectric" "X5R"
			(at 325.5 -79.5 0)
			(layer "B.Fab")
			(hide yes)
			(effects
				(font
					(size 1 1)
					(thickness 0.15)
				)
				(justify mirror)
			)
		)
		(property "License" "Apache-2.0"
			(at 325.5 -79.5 0)
			(layer "B.Fab")
			(hide yes)
			(effects
				(font
					(size 1 1)
					(thickness 0.15)
				)
				(justify mirror)
			)
		)
		(property "MPN" "GRM155R61H104KE14D"
			(at 325.5 -79.5 0)
			(layer "B.Fab")
			(hide yes)
			(effects
				(font
					(size 1 1)
					(thickness 0.15)
				)
				(justify mirror)
			)
		)
		(property "Manufacturer" "Murata"
			(at 325.5 -79.5 0)
			(layer "B.Fab")
			(hide yes)
			(effects
				(font
					(size 1 1)
					(thickness 0.15)
				)
				(justify mirror)
			)
		)
		(property "Val" "100n"
			(at 325.5 -79.5 0)
			(layer "B.Fab")
			(hide yes)
			(effects
				(font
					(size 1 1)
					(thickness 0.15)
				)
				(justify mirror)
			)
		)
		(property "Voltage" "50V"
			(at 325.5 -79.5 0)
			(layer "B.Fab")
			(hide yes)
			(effects
				(font
					(size 1 1)
					(thickness 0.15)
				)
				(justify mirror)
			)
		)
		(sheetname "FPGA Bank 16 & 17")
		(sheetfile "fpga-bank-16-17.kicad_sch")
		(attr smd)
		(fp_rect
			(start -0.925 0.47)
			(end 0.925 -0.47)
			(stroke
				(width 0.05)
				(type default)
			)
			(fill no)
			(layer "B.CrtYd")
		)
		(fp_line
			(start 0.504 -0.248)
			(end -0.494 -0.248)
			(stroke
				(width 0.15)
				(type solid)
			)
			(layer "B.Fab")
		)
		(fp_line
			(start -0.494 -0.248)
			(end -0.494 0.25)
			(stroke
				(width 0.15)
				(type solid)
			)
			(layer "B.Fab")
		)
		(fp_line
			(start 0.504 0.25)
			(end 0.504 -0.248)
			(stroke
				(width 0.15)
				(type solid)
			)
			(layer "B.Fab")
		)
		(fp_line
			(start -0.494 0.25)
			(end 0.504 0.25)
			(stroke
				(width 0.15)
				(type solid)
			)
			(layer "B.Fab")
		)
		(pad "1" smd roundrect
			(at -0.48 0 90)
			(size 0.59 0.64)
			(layers "B.Cu" "B.Mask" "B.Paste")
			(roundrect_rratio 0.25)
			(net 1 "GND")
			(pintype "passive")
		)
		(pad "2" smd roundrect
			(at 0.48 0 90)
			(size 0.59 0.64)
			(layers "B.Cu" "B.Mask" "B.Paste")
			(roundrect_rratio 0.25)
			(net 24 "+3V3")
			(pintype "passive")
		)
	)
	(footprint "antmicro-footprints:C_0402_1005Metric"
		(layer "B.Cu")
		(at 198 117.5 180)
		(descr "Capacitor SMD 0402")
		(tags "capacitor SMD 0402")
		(property "Reference" "C93"
			(at -0.8 0.45 0)
			(layer "B.SilkS")
			(effects
				(font
					(size 0.7 0.7)
					(thickness 0.15)
				)
				(justify left bottom mirror)
			)
		)
		(property "Value" "C_100n_0402"
			(at 0 -1.169 0)
			(layer "B.Fab")
			(effects
				(font
					(size 0.7 0.7)
					(thickness 0.15)
				)
				(justify left bottom mirror)
			)
		)
		(property "Description" "SMD Multilayer Ceramic Capacitor, 0.1 µF, 50 V, 0402 [1005 Metric], ± 10%, X5R, GRM Series"
			(at 0 0 180)
			(layer "F.Fab")
			(hide yes)
			(effects
				(font
					(size 1.27 1.27)
					(thickness 0.15)
				)
			)
		)
		(property "Author" "Antmicro"
			(at 396 235 0)
			(layer "B.Fab")
			(hide yes)
			(effects
				(font
					(size 1 1)
					(thickness 0.15)
				)
				(justify mirror)
			)
		)
		(property "Dielectric" "X5R"
			(at 396 235 0)
			(layer "B.Fab")
			(hide yes)
			(effects
				(font
					(size 1 1)
					(thickness 0.15)
				)
				(justify mirror)
			)
		)
		(property "License" "Apache-2.0"
			(at 396 235 0)
			(layer "B.Fab")
			(hide yes)
			(effects
				(font
					(size 1 1)
					(thickness 0.15)
				)
				(justify mirror)
			)
		)
		(property "MPN" "GRM155R61H104KE14D"
			(at 396 235 0)
			(layer "B.Fab")
			(hide yes)
			(effects
				(font
					(size 1 1)
					(thickness 0.15)
				)
				(justify mirror)
			)
		)
		(property "Manufacturer" "Murata"
			(at 396 235 0)
			(layer "B.Fab")
			(hide yes)
			(effects
				(font
					(size 1 1)
					(thickness 0.15)
				)
				(justify mirror)
			)
		)
		(property "Val" "100n"
			(at 396 235 0)
			(layer "B.Fab")
			(hide yes)
			(effects
				(font
					(size 1 1)
					(thickness 0.15)
				)
				(justify mirror)
			)
		)
		(property "Voltage" "50V"
			(at 396 235 0)
			(layer "B.Fab")
			(hide yes)
			(effects
				(font
					(size 1 1)
					(thickness 0.15)
				)
				(justify mirror)
			)
		)
		(sheetname "FPGA Bank 18 & 32")
		(sheetfile "fpga-bank-18-32.kicad_sch")
		(attr smd)
		(fp_rect
			(start -0.925 0.47)
			(end 0.925 -0.47)
			(stroke
				(width 0.05)
				(type default)
			)
			(fill no)
			(layer "B.CrtYd")
		)
		(fp_line
			(start 0.504 0.25)
			(end 0.504 -0.248)
			(stroke
				(width 0.15)
				(type solid)
			)
			(layer "B.Fab")
		)
		(fp_line
			(start 0.504 -0.248)
			(end -0.494 -0.248)
			(stroke
				(width 0.15)
				(type solid)
			)
			(layer "B.Fab")
		)
		(fp_line
			(start -0.494 0.25)
			(end 0.504 0.25)
			(stroke
				(width 0.15)
				(type solid)
			)
			(layer "B.Fab")
		)
		(fp_line
			(start -0.494 -0.248)
			(end -0.494 0.25)
			(stroke
				(width 0.15)
				(type solid)
			)
			(layer "B.Fab")
		)
		(pad "1" smd roundrect
			(at -0.48 0 180)
			(size 0.59 0.64)
			(layers "B.Cu" "B.Mask" "B.Paste")
			(roundrect_rratio 0.25)
			(net 1 "GND")
			(pintype "passive")
		)
		(pad "2" smd roundrect
			(at 0.48 0 180)
			(size 0.59 0.64)
			(layers "B.Cu" "B.Mask" "B.Paste")
			(roundrect_rratio 0.25)
			(net 24 "+3V3")
			(pintype "passive")
		)
	)
)
